(kicad_pcb
	(version 20260206)
	(generator "pcbnew")
	(generator_version "10.0")
	(general
		(thickness 1.6)
		(legacy_teardrops no)
	)
	(paper "A4")
	(title_block
		(title "12092022_DA0F0TMDCD0_F0T_Management_Board_D_brd_V3_OCP.brd")
		(comment 1 "Grand Teton / footprint 124 of 1440 (U5), pads 563-624 of 624")
	)
	(layers
		(0 "F.Cu" signal "TOP")
		(4 "In1.Cu" signal "GND")
		(6 "In2.Cu" signal "IN1")
		(8 "In3.Cu" signal "GND1")
		(10 "In4.Cu" signal "IN2")
		(12 "In5.Cu" signal "VCC")
		(14 "In6.Cu" signal "VCC1")
		(16 "In7.Cu" signal "IN3")
		(18 "In8.Cu" signal "GND2")
		(20 "In9.Cu" signal "IN4")
		(22 "In10.Cu" signal "GND3")
		(2 "B.Cu" signal "BOTTOM")
		(9 "F.Adhes" user "F.Adhesive")
		(11 "B.Adhes" user "B.Adhesive")
		(13 "F.Paste" user "Package Geometry/Pastemask Top")
		(15 "B.Paste" user "Package Geometry/Pastemask Bottom")
		(5 "F.SilkS" user "Ref Des/Silkscreen Top")
		(7 "B.SilkS" user "Ref Des/Silkscreen Bottom")
		(1 "F.Mask" user "Board Geometry/Soldermask Top")
		(3 "B.Mask" user "Board Geometry/Soldermask Bottom")
		(17 "Dwgs.User" user "User.Drawings")
		(19 "Cmts.User" user "User.Comments")
		(21 "Eco1.User" user "User.Eco1")
		(23 "Eco2.User" user "User.Eco2")
		(25 "Edge.Cuts" user "Board Geometry/Outline")
		(27 "Margin" user)
		(31 "F.CrtYd" user "Package Geometry/Place Bound Top")
		(29 "B.CrtYd" user "Package Geometry/Place Bound Bottom")
		(35 "F.Fab" user "Ref Des/Assembly Top")
		(33 "B.Fab" user "Ref Des/Assembly Bottom")
	)
	(footprint ""
		(layer "F.Cu")
		(at 54.894988 -49.37125 180)
		(property "Reference" "U5"
			(at -11.094212 -12.07262 0)
			(unlocked yes)
			(layer "F.SilkS")
			(effects
				(font
					(size 0.7874 0.5842)
					(thickness 0.1524)
				)
				(justify left)
			)
		)
		(property "Value" ""
			(at 0 0 180)
			(layer "F.Fab")
			(effects
				(font
					(size 1.27 1.27)
				)
			)
		)
		(duplicate_pad_numbers_are_jumpers no)
		(pad "U25" smd circle
			(at 9.19988 2.800096 180)
			(size 0.4064 0.4064)
			(layers "F.Cu" "F.Mask" "F.Paste")
			(net "IRQ_CPU1_VRHOT_N")
		)
		(pad "U26" smd circle
			(at 9.99998 2.800096 180)
			(size 0.4064 0.4064)
			(layers "F.Cu" "F.Mask" "F.Paste")
			(net "FM_BIOS_POST_CMPLT_BMC_N")
		)
		(pad "V1" smd circle
			(at -9.99998 3.599942 180)
			(size 0.4064 0.4064)
			(layers "F.Cu" "F.Mask" "F.Paste")
			(net "M_BMC_DDR4_DQS1_N")
		)
		(pad "V2" smd circle
			(at -9.19988 3.599942 180)
			(size 0.4064 0.4064)
			(layers "F.Cu" "F.Mask" "F.Paste")
			(net "M_BMC_DDR4_DQS1_P")
		)
		(pad "V3" smd circle
			(at -8.400034 3.599942 180)
			(size 0.4064 0.4064)
			(layers "F.Cu" "F.Mask" "F.Paste")
			(net "M_BMC_DDR4_DQ<9>")
		)
		(pad "V4" smd circle
			(at -7.599934 3.599942 180)
			(size 0.4064 0.4064)
			(layers "F.Cu" "F.Mask" "F.Paste")
			(net "M_BMC_DDR4_DQ<14>")
		)
		(pad "V5" smd circle
			(at -6.800088 3.599942 180)
			(size 0.4064 0.4064)
			(layers "F.Cu" "F.Mask" "F.Paste")
			(net "GND")
		)
		(pad "V6" smd circle
			(at -5.999988 3.599942 180)
			(size 0.4064 0.4064)
			(layers "F.Cu" "F.Mask" "F.Paste")
			(net "P1V8_AUX")
		)
		(pad "V8" smd circle
			(at -4.400042 3.599942 180)
			(size 0.4064 0.4064)
			(layers "F.Cu" "F.Mask" "F.Paste")
			(net "P1V8_STBY_DP_VCC18A")
		)
		(pad "V9" smd circle
			(at -3.599942 3.599942 180)
			(size 0.4064 0.4064)
			(layers "F.Cu" "F.Mask" "F.Paste")
			(net "P1V8_STBY_PE_VCC18A")
		)
		(pad "V10" smd circle
			(at -2.800096 3.599942 180)
			(size 0.4064 0.4064)
			(layers "F.Cu" "F.Mask" "F.Paste")
			(net "P1V8_STBY_RC_VCC18A")
		)
		(pad "V11" smd circle
			(at -1.999996 3.599942 180)
			(size 0.4064 0.4064)
			(layers "F.Cu" "F.Mask" "F.Paste")
			(net "GND")
		)
		(pad "V12" smd circle
			(at -1.199896 3.599942 180)
			(size 0.4064 0.4064)
			(layers "F.Cu" "F.Mask" "F.Paste")
			(net "GND")
		)
		(pad "V13" smd circle
			(at -0.40005 3.599942 180)
			(size 0.4064 0.4064)
			(layers "F.Cu" "F.Mask" "F.Paste")
			(net "P1V8_AUX")
		)
		(pad "V14" smd circle
			(at 0.40005 3.599942 180)
			(size 0.4064 0.4064)
			(layers "F.Cu" "F.Mask" "F.Paste")
			(net "GND")
		)
		(pad "V15" smd circle
			(at 1.199896 3.599942 180)
			(size 0.4064 0.4064)
			(layers "F.Cu" "F.Mask" "F.Paste")
			(net "GND")
		)
		(pad "V16" smd circle
			(at 1.999996 3.599942 180)
			(size 0.4064 0.4064)
			(layers "F.Cu" "F.Mask" "F.Paste")
			(net "GND")
		)
		(pad "V17" smd circle
			(at 2.800096 3.599942 180)
			(size 0.4064 0.4064)
			(layers "F.Cu" "F.Mask" "F.Paste")
			(net "GND")
		)
		(pad "V18" smd circle
			(at 3.599942 3.599942 180)
			(size 0.4064 0.4064)
			(layers "F.Cu" "F.Mask" "F.Paste")
			(net "GND")
		)
		(pad "V19" smd circle
			(at 4.400042 3.599942 180)
			(size 0.4064 0.4064)
			(layers "F.Cu" "F.Mask" "F.Paste")
			(net "GND")
		)
		(pad "V21" smd circle
			(at 5.999988 3.599942 180)
			(size 0.4064 0.4064)
			(layers "F.Cu" "F.Mask" "F.Paste")
			(net "P3V3_STBY_DACAV33")
		)
		(pad "V22" smd circle
			(at 6.800088 3.599942 180)
			(size 0.4064 0.4064)
			(layers "F.Cu" "F.Mask" "F.Paste")
			(net "P1V2_P1V0_I3C_VDDL1")
		)
		(pad "V23" smd circle
			(at 7.599934 3.599942 180)
			(size 0.4064 0.4064)
			(layers "F.Cu" "F.Mask" "F.Paste")
			(net "P3V3_RTC_AUX")
		)
		(pad "V24" smd circle
			(at 8.400034 3.599942 180)
			(size 0.4064 0.4064)
			(layers "F.Cu" "F.Mask" "F.Paste")
			(net "IRQ_OC_DETECT_EN_N")
		)
		(pad "V25" smd circle
			(at 9.19988 3.599942 180)
			(size 0.4064 0.4064)
			(layers "F.Cu" "F.Mask" "F.Paste")
			(net "IRQ_OC_DETECT_N")
		)
		(pad "V26" smd circle
			(at 9.99998 3.599942 180)
			(size 0.4064 0.4064)
			(layers "F.Cu" "F.Mask" "F.Paste")
			(net "IRQ_CPU0_VRHOT_N")
		)
		(pad "W1" smd circle
			(at -9.99998 4.400042 180)
			(size 0.4064 0.4064)
			(layers "F.Cu" "F.Mask" "F.Paste")
			(net "M_BMC_DDR4_DQ<10>")
		)
		(pad "W2" smd circle
			(at -9.19988 4.400042 180)
			(size 0.4064 0.4064)
			(layers "F.Cu" "F.Mask" "F.Paste")
			(net "M_BMC_DDR4_DQ<8>")
		)
		(pad "W3" smd circle
			(at -8.400034 4.400042 180)
			(size 0.4064 0.4064)
			(layers "F.Cu" "F.Mask" "F.Paste")
			(net "M_BMC_DDR4_DQ<11>")
		)
		(pad "W4" smd circle
			(at -7.599934 4.400042 180)
			(size 0.4064 0.4064)
			(layers "F.Cu" "F.Mask" "F.Paste")
			(net "M_BMC_DDR4_DQ<12>")
		)
		(pad "W5" smd circle
			(at -6.800088 4.400042 180)
			(size 0.4064 0.4064)
			(layers "F.Cu" "F.Mask" "F.Paste")
			(net "GND")
		)
		(pad "W6" smd circle
			(at -5.999988 4.400042 180)
			(size 0.4064 0.4064)
			(layers "F.Cu" "F.Mask" "F.Paste")
			(net "GND")
		)
		(pad "W8" smd circle
			(at -4.400042 4.400042 180)
			(size 0.4064 0.4064)
			(layers "F.Cu" "F.Mask" "F.Paste")
			(net "GND")
		)
		(pad "W9" smd circle
			(at -3.599942 4.400042 180)
			(size 0.4064 0.4064)
			(layers "F.Cu" "F.Mask" "F.Paste")
			(net "GND")
		)
		(pad "W10" smd circle
			(at -2.800096 4.400042 180)
			(size 0.4064 0.4064)
			(layers "F.Cu" "F.Mask" "F.Paste")
			(net "GND")
		)
		(pad "W11" smd circle
			(at -1.999996 4.400042 180)
			(size 0.4064 0.4064)
			(layers "F.Cu" "F.Mask" "F.Paste")
			(net "GND")
		)
		(pad "W12" smd circle
			(at -1.199896 4.400042 180)
			(size 0.4064 0.4064)
			(layers "F.Cu" "F.Mask" "F.Paste")
			(net "GND")
		)
		(pad "W13" smd circle
			(at -0.40005 4.400042 180)
			(size 0.4064 0.4064)
			(layers "F.Cu" "F.Mask" "F.Paste")
			(net "P1V8_AUX")
		)
		(pad "W14" smd circle
			(at 0.40005 4.400042 180)
			(size 0.4064 0.4064)
			(layers "F.Cu" "F.Mask" "F.Paste")
			(net "P1V8_AUX")
		)
		(pad "W15" smd circle
			(at 1.199896 4.400042 180)
			(size 0.4064 0.4064)
			(layers "F.Cu" "F.Mask" "F.Paste")
			(net "PGPPA_BMC_AUX")
		)
		(pad "W16" smd circle
			(at 1.999996 4.400042 180)
			(size 0.4064 0.4064)
			(layers "F.Cu" "F.Mask" "F.Paste")
			(net "P3V3_AUX")
		)
		(pad "W17" smd circle
			(at 2.800096 4.400042 180)
			(size 0.4064 0.4064)
			(layers "F.Cu" "F.Mask" "F.Paste")
			(net "P3V3_AUX")
		)
		(pad "W18" smd circle
			(at 3.599942 4.400042 180)
			(size 0.4064 0.4064)
			(layers "F.Cu" "F.Mask" "F.Paste")
			(net "P3V3_AUX")
		)
		(pad "W19" smd circle
			(at 4.400042 4.400042 180)
			(size 0.4064 0.4064)
			(layers "F.Cu" "F.Mask" "F.Paste")
			(net "P3V3_AUX")
		)
		(pad "W21" smd circle
			(at 5.999988 4.400042 180)
			(size 0.4064 0.4064)
			(layers "F.Cu" "F.Mask" "F.Paste")
			(net "P3V3_STBY_DACAV33")
		)
		(pad "W22" smd circle
			(at 6.800088 4.400042 180)
			(size 0.4064 0.4064)
			(layers "F.Cu" "F.Mask" "F.Paste")
			(net "GND")
		)
		(pad "W23" smd circle
			(at 7.599934 4.400042 180)
			(size 0.4064 0.4064)
			(layers "F.Cu" "F.Mask" "F.Paste")
			(net "BMC_PWR_LED")
		)
		(pad "W24" smd circle
			(at 8.400034 4.400042 180)
			(size 0.4064 0.4064)
			(layers "F.Cu" "F.Mask" "F.Paste")
			(net "SYS_BMC_PWRBTN_R1_N")
		)
		(pad "W25" smd circle
			(at 9.19988 4.400042 180)
			(size 0.4064 0.4064)
			(layers "F.Cu" "F.Mask" "F.Paste")
			(net "GND")
		)
		(pad "W26" smd circle
			(at 9.99998 4.400042 180)
			(size 0.4064 0.4064)
			(layers "F.Cu" "F.Mask" "F.Paste")
			(net "PWRGD_CPUPWRGD_LVC1")
		)
		(pad "Y1" smd circle
			(at -9.99998 5.199888 180)
			(size 0.4064 0.4064)
			(layers "F.Cu" "F.Mask" "F.Paste")
			(net "Net_60")
		)
		(pad "Y2" smd circle
			(at -9.19988 5.199888 180)
			(size 0.4064 0.4064)
			(layers "F.Cu" "F.Mask" "F.Paste")
			(net "Net_59")
		)
		(pad "Y3" smd circle
			(at -8.400034 5.199888 180)
			(size 0.4064 0.4064)
			(layers "F.Cu" "F.Mask" "F.Paste")
			(net "Net_58")
		)
		(pad "Y4" smd circle
			(at -7.599934 5.199888 180)
			(size 0.4064 0.4064)
			(layers "F.Cu" "F.Mask" "F.Paste")
			(net "Net_57")
		)
		(pad "Y5" smd circle
			(at -6.800088 5.199888 180)
			(size 0.4064 0.4064)
			(layers "F.Cu" "F.Mask" "F.Paste")
			(net "Net_64")
		)
		(pad "Y6" smd circle
			(at -5.999988 5.199888 180)
			(size 0.4064 0.4064)
			(layers "F.Cu" "F.Mask" "F.Paste")
			(net "GND")
		)
		(pad "Y21" smd circle
			(at 5.999988 5.199888 180)
			(size 0.4064 0.4064)
			(layers "F.Cu" "F.Mask" "F.Paste")
			(net "A_BMC_ADCAV33")
		)
		(pad "Y22" smd circle
			(at 6.800088 5.199888 180)
			(size 0.4064 0.4064)
			(layers "F.Cu" "F.Mask" "F.Paste")
			(net "GND")
		)
		(pad "Y23" smd circle
			(at 7.599934 5.199888 180)
			(size 0.4064 0.4064)
			(layers "F.Cu" "F.Mask" "F.Paste")
			(net "BMC_HEARTBEAT_N")
		)
		(pad "Y24" smd circle
			(at 8.400034 5.199888 180)
			(size 0.4064 0.4064)
			(layers "F.Cu" "F.Mask" "F.Paste")
			(net "GPU_NVS_PWR_BRAKE_R_N")
		)
		(pad "Y25" smd circle
			(at 9.19988 5.199888 180)
			(size 0.4064 0.4064)
			(layers "F.Cu" "F.Mask" "F.Paste")
			(net "FM_PCH_BEEP_LED")
		)
		(pad "Y26" smd circle
			(at 9.99998 5.199888 180)
			(size 0.4064 0.4064)
			(layers "F.Cu" "F.Mask" "F.Paste")
			(net "FM_HDD_LED_N")
		)
	)
)
